# T6G (Grand Teton) — schematic netlist excerpt (pin names and nets, part order shuffled) for the footprints in the layout excerpt that follows; sources: Cadence DE-HDL packaged netlist, KiCad conversion of 04192023_DAF0TMB3IC0_F0TG_MB_C_brd_V02_OCP.brd

R1161  Q_RES  0 5% CHIP  pkg 0402LF  page 161 : A = SMB_CPU1_SEC_R_SCL ; B = SMB_CPU1_SEC_SCL
C6613  Q_CAP_DIFFBUS  DIFF BUS_0.22UF 6.3V 20% X6S  pkg C0201  page 308 : \1\ = P5E_CPU0_P3_TX_BUF_C_DP<8> ; \2\ = P5E_CPU0_P3_TX_BUF_DP<8>
R392  Q_RES  2.2K 5% EMPTY  pkg 0402LF  page 27 : A = PVDD18_S5_P0 ; B = CPU0_SA0

(kicad_pcb
	(version 20260206)
	(generator "pcbnew")
	(generator_version "10.0")
	(general
		(thickness 1.6)
		(legacy_teardrops no)
	)
	(paper "A4")
	(title_block
		(title "04192023_DAF0TMB3IC0_F0TG_MB_C_brd_V02_OCP.brd")
		(comment 1 "Grand Teton / footprints 7074-7076 of 8354")
	)
	(layers
		(0 "F.Cu" signal "TOP")
		(4 "In1.Cu" signal "GND")
		(6 "In2.Cu" signal "IN1")
		(8 "In3.Cu" signal "GND1")
		(10 "In4.Cu" signal "IN2")
		(12 "In5.Cu" signal "GND2")
		(14 "In6.Cu" signal "IN3")
		(16 "In7.Cu" signal "GND3")
		(18 "In8.Cu" signal "VCC")
		(20 "In9.Cu" signal "VCC1")
		(22 "In10.Cu" signal "GND4")
		(24 "In11.Cu" signal "IN4")
		(26 "In12.Cu" signal "GND5")
		(28 "In13.Cu" signal "IN5")
		(30 "In14.Cu" signal "GND6")
		(32 "In15.Cu" signal "IN6")
		(34 "In16.Cu" signal "GND7")
		(2 "B.Cu" signal "BOTTOM")
		(9 "F.Adhes" user "F.Adhesive")
		(11 "B.Adhes" user "B.Adhesive")
		(13 "F.Paste" user "Package Geometry/Pastemask Top")
		(15 "B.Paste" user "Package Geometry/Pastemask Bottom")
		(5 "F.SilkS" user "Ref Des/Silkscreen Top")
		(7 "B.SilkS" user "Ref Des/Silkscreen Bottom")
		(1 "F.Mask" user "Board Geometry/Soldermask Top")
		(3 "B.Mask" user "Board Geometry/Soldermask Bottom")
		(17 "Dwgs.User" user "User.Drawings")
		(19 "Cmts.User" user "User.Comments")
		(21 "Eco1.User" user "User.Eco1")
		(23 "Eco2.User" user "User.Eco2")
		(25 "Edge.Cuts" user "Board Geometry/Outline")
		(27 "Margin" user)
		(31 "F.CrtYd" user "Package Geometry/Place Bound Top")
		(29 "B.CrtYd" user "Package Geometry/Place Bound Bottom")
		(35 "F.Fab" user "Ref Des/Assembly Top")
		(33 "B.Fab" user "Ref Des/Assembly Bottom")
	)
	(footprint ""
		(layer "B.Cu")
		(at 338.830158 -309.214012 90)
		(property "Reference" "R392"
			(at 0 0 90)
			(layer "B.SilkS")
			(hide yes)
			(effects
				(font
					(size 1.27 1.27)
				)
				(justify mirror)
			)
		)
		(property "Value" ""
			(at 0 0 90)
			(layer "B.Fab")
			(effects
				(font
					(size 1.27 1.27)
				)
				(justify mirror)
			)
		)
		(duplicate_pad_numbers_are_jumpers no)
		(fp_line
			(start 0.7874 -0.4064)
			(end -0.7874 -0.4064)
			(stroke
				(width 0.1524)
				(type default)
			)
			(layer "B.SilkS")
		)
		(fp_line
			(start -0.7874 -0.4064)
			(end -0.7874 0.4064)
			(stroke
				(width 0.1524)
				(type default)
			)
			(layer "B.SilkS")
		)
		(fp_line
			(start 0.7874 0.4064)
			(end 0.7874 -0.4064)
			(stroke
				(width 0.1524)
				(type default)
			)
			(layer "B.SilkS")
		)
		(fp_line
			(start -0.7874 0.4064)
			(end 0.7874 0.4064)
			(stroke
				(width 0.1524)
				(type default)
			)
			(layer "B.SilkS")
		)
		(fp_line
			(start 0.67945 -0.305054)
			(end 0.12065 -0.305054)
			(stroke
				(width 0.1)
				(type default)
			)
			(layer "B.Fab")
		)
		(fp_line
			(start 0.12065 -0.305054)
			(end 0.12065 -0.2794)
			(stroke
				(width 0.1)
				(type default)
			)
			(layer "B.Fab")
		)
		(fp_line
			(start -0.12065 -0.3048)
			(end -0.67945 -0.3048)
			(stroke
				(width 0.1)
				(type default)
			)
			(layer "B.Fab")
		)
		(fp_line
			(start -0.67945 -0.3048)
			(end -0.67945 0.3048)
			(stroke
				(width 0.1)
				(type default)
			)
			(layer "B.Fab")
		)
		(fp_line
			(start 0.12065 -0.2794)
			(end -0.12065 -0.2794)
			(stroke
				(width 0.1)
				(type default)
			)
			(layer "B.Fab")
		)
		(fp_line
			(start -0.12065 -0.2794)
			(end -0.12065 -0.3048)
			(stroke
				(width 0.1)
				(type default)
			)
			(layer "B.Fab")
		)
		(fp_line
			(start 0.12065 0.2794)
			(end 0.12065 0.3048)
			(stroke
				(width 0.1)
				(type default)
			)
			(layer "B.Fab")
		)
		(fp_line
			(start -0.120396 0.2794)
			(end 0.12065 0.2794)
			(stroke
				(width 0.1)
				(type default)
			)
			(layer "B.Fab")
		)
		(fp_line
			(start 0.67945 0.3048)
			(end 0.67945 -0.305054)
			(stroke
				(width 0.1)
				(type default)
			)
			(layer "B.Fab")
		)
		(fp_line
			(start 0.12065 0.3048)
			(end 0.67945 0.3048)
			(stroke
				(width 0.1)
				(type default)
			)
			(layer "B.Fab")
		)
		(fp_line
			(start -0.120396 0.3048)
			(end -0.120396 0.2794)
			(stroke
				(width 0.1)
				(type default)
			)
			(layer "B.Fab")
		)
		(fp_line
			(start -0.67945 0.3048)
			(end -0.120396 0.3048)
			(stroke
				(width 0.1)
				(type default)
			)
			(layer "B.Fab")
		)
		(pad "1" smd circle
			(at 0.40005 0 270)
			(size 0 0)
			(layers "B.Cu" "B.Mask" "B.Paste")
			(net "PVDD18_S5_P0")
		)
		(pad "2" smd circle
			(at -0.40005 0 270)
			(size 0 0)
			(layers "B.Cu" "B.Mask" "B.Paste")
			(net "CPU0_SA0")
		)
	)
	(footprint ""
		(layer "B.Cu")
		(at 238.379 -234.061 90)
		(property "Reference" "R1161"
			(at 0 0 90)
			(layer "B.SilkS")
			(hide yes)
			(effects
				(font
					(size 1.27 1.27)
				)
				(justify mirror)
			)
		)
		(property "Value" ""
			(at 0 0 90)
			(layer "B.Fab")
			(effects
				(font
					(size 1.27 1.27)
				)
				(justify mirror)
			)
		)
		(duplicate_pad_numbers_are_jumpers no)
		(fp_line
			(start 0.7874 -0.4064)
			(end -0.7874 -0.4064)
			(stroke
				(width 0.1524)
				(type default)
			)
			(layer "B.SilkS")
		)
		(fp_line
			(start -0.7874 -0.4064)
			(end -0.7874 0.4064)
			(stroke
				(width 0.1524)
				(type default)
			)
			(layer "B.SilkS")
		)
		(fp_line
			(start 0.7874 0.4064)
			(end 0.7874 -0.4064)
			(stroke
				(width 0.1524)
				(type default)
			)
			(layer "B.SilkS")
		)
		(fp_line
			(start -0.7874 0.4064)
			(end 0.7874 0.4064)
			(stroke
				(width 0.1524)
				(type default)
			)
			(layer "B.SilkS")
		)
		(fp_line
			(start 0.67945 -0.305054)
			(end 0.12065 -0.305054)
			(stroke
				(width 0.1)
				(type default)
			)
			(layer "B.Fab")
		)
		(fp_line
			(start 0.12065 -0.305054)
			(end 0.12065 -0.2794)
			(stroke
				(width 0.1)
				(type default)
			)
			(layer "B.Fab")
		)
		(fp_line
			(start -0.12065 -0.3048)
			(end -0.67945 -0.3048)
			(stroke
				(width 0.1)
				(type default)
			)
			(layer "B.Fab")
		)
		(fp_line
			(start -0.67945 -0.3048)
			(end -0.67945 0.3048)
			(stroke
				(width 0.1)
				(type default)
			)
			(layer "B.Fab")
		)
		(fp_line
			(start 0.12065 -0.2794)
			(end -0.12065 -0.2794)
			(stroke
				(width 0.1)
				(type default)
			)
			(layer "B.Fab")
		)
		(fp_line
			(start -0.12065 -0.2794)
			(end -0.12065 -0.3048)
			(stroke
				(width 0.1)
				(type default)
			)
			(layer "B.Fab")
		)
		(fp_line
			(start 0.12065 0.2794)
			(end 0.12065 0.3048)
			(stroke
				(width 0.1)
				(type default)
			)
			(layer "B.Fab")
		)
		(fp_line
			(start -0.120396 0.2794)
			(end 0.12065 0.2794)
			(stroke
				(width 0.1)
				(type default)
			)
			(layer "B.Fab")
		)
		(fp_line
			(start 0.67945 0.3048)
			(end 0.67945 -0.305054)
			(stroke
				(width 0.1)
				(type default)
			)
			(layer "B.Fab")
		)
		(fp_line
			(start 0.12065 0.3048)
			(end 0.67945 0.3048)
			(stroke
				(width 0.1)
				(type default)
			)
			(layer "B.Fab")
		)
		(fp_line
			(start -0.120396 0.3048)
			(end -0.120396 0.2794)
			(stroke
				(width 0.1)
				(type default)
			)
			(layer "B.Fab")
		)
		(fp_line
			(start -0.67945 0.3048)
			(end -0.120396 0.3048)
			(stroke
				(width 0.1)
				(type default)
			)
			(layer "B.Fab")
		)
		(pad "1" smd circle
			(at 0.40005 0 270)
			(size 0 0)
			(layers "B.Cu" "B.Mask" "B.Paste")
			(net "SMB_CPU1_SEC_R_SCL")
		)
		(pad "2" smd circle
			(at -0.40005 0 270)
			(size 0 0)
			(layers "B.Cu" "B.Mask" "B.Paste")
			(net "SMB_CPU1_SEC_SCL")
		)
	)
	(footprint ""
		(layer "B.Cu")
		(at 397.820642 -416.899344 90)
		(property "Reference" "C6613"
			(at 0 0 90)
			(layer "B.SilkS")
			(hide yes)
			(effects
				(font
					(size 1.27 1.27)
				)
				(justify mirror)
			)
		)
		(property "Value" ""
			(at 0 0 90)
			(layer "B.Fab")
			(effects
				(font
					(size 1.27 1.27)
				)
				(justify mirror)
			)
		)
		(duplicate_pad_numbers_are_jumpers no)
		(fp_line
			(start 0.299974 -0.150114)
			(end -0.299974 -0.150114)
			(stroke
				(width 0.1)
				(type default)
			)
			(layer "B.Fab")
		)
		(fp_line
			(start -0.299974 -0.150114)
			(end -0.299974 0.150114)
			(stroke
				(width 0.1)
				(type default)
			)
			(layer "B.Fab")
		)
		(fp_line
			(start 0.299974 0.150114)
			(end 0.299974 -0.150114)
			(stroke
				(width 0.1)
				(type default)
			)
			(layer "B.Fab")
		)
		(fp_line
			(start -0.299974 0.150114)
			(end 0.299974 0.150114)
			(stroke
				(width 0.1)
				(type default)
			)
			(layer "B.Fab")
		)
		(pad "1" smd rect
			(at 0.2667 0 270)
			(size 0.3048 0.381)
			(layers "B.Cu" "B.Mask" "B.Paste")
			(net "P5E_CPU0_P3_TX_BUF_C_DP<8>")
		)
		(pad "2" smd rect
			(at -0.2667 0 270)
			(size 0.3048 0.381)
			(layers "B.Cu" "B.Mask" "B.Paste")
			(net "P5E_CPU0_P3_TX_BUF_DP<8>")
		)
	)
)
